(kicad_pcb
	(version 20260206)
	(generator "pcbnew")
	(generator_version "10.0")
	(general
		(thickness 1.6)
		(legacy_teardrops no)
	)
	(paper "A4")
	(title_block
		(title "peb — Lightning_PEB_BRD.brd")
		(comment 1 "Lightning (Wiwynn / Facebook NVMe JBOF) / footprints 2184-2190 of 2563")
	)
	(layers
		(0 "F.Cu" signal "TOP")
		(4 "In1.Cu" signal "L2GND")
		(6 "In2.Cu" signal "L3")
		(8 "In3.Cu" signal "L4VCC")
		(10 "In4.Cu" signal "L5VCC")
		(12 "In5.Cu" signal "L6")
		(14 "In6.Cu" signal "L7GND")
		(2 "B.Cu" signal "BOTTOM")
		(9 "F.Adhes" user "F.Adhesive")
		(11 "B.Adhes" user "B.Adhesive")
		(13 "F.Paste" user "Package Geometry/Pastemask Top")
		(15 "B.Paste" user "Package Geometry/Pastemask Bottom")
		(5 "F.SilkS" user "Ref Des/Silkscreen Top")
		(7 "B.SilkS" user "Ref Des/Silkscreen Bottom")
		(1 "F.Mask" user "Board Geometry/Soldermask Top")
		(3 "B.Mask" user "Board Geometry/Soldermask Bottom")
		(17 "Dwgs.User" user "User.Drawings")
		(19 "Cmts.User" user "User.Comments")
		(21 "Eco1.User" user "User.Eco1")
		(23 "Eco2.User" user "User.Eco2")
		(25 "Edge.Cuts" user "Board Geometry/Outline")
		(27 "Margin" user)
		(31 "F.CrtYd" user "Package Geometry/Place Bound Top")
		(29 "B.CrtYd" user "Package Geometry/Place Bound Bottom")
		(35 "F.Fab" user "Ref Des/Assembly Top")
		(33 "B.Fab" user "Ref Des/Assembly Bottom")
	)
	(footprint ""
		(layer "B.Cu")
		(at 50.2158 -115.90909)
		(property "Reference" "R471"
			(at 0 0 0)
			(layer "B.SilkS")
			(hide yes)
			(effects
				(font
					(size 1.27 1.27)
				)
				(justify mirror)
			)
		)
		(property "Value" "0R2J-2-GP"
			(at -0.064008 -3.993896 0)
			(unlocked yes)
			(layer "B.Fab")
			(hide yes)
			(effects
				(font
					(size 1.016 1.016)
					(thickness 0.1524)
				)
				(justify mirror)
			)
		)
		(property "Device Type" "R402H16"
			(at -0.064008 -5.517896 0)
			(unlocked yes)
			(layer "B.Fab")
			(hide yes)
			(effects
				(font
					(size 1.016 1.016)
					(thickness 0.1524)
				)
				(justify mirror)
			)
		)
		(duplicate_pad_numbers_are_jumpers no)
		(fp_line
			(start -0.508 -0.9398)
			(end 0.508 -0.9398)
			(stroke
				(width 0.1524)
				(type default)
			)
			(layer "B.SilkS")
		)
		(fp_line
			(start 0.508 -0.9398)
			(end 0.508 0.9398)
			(stroke
				(width 0.1524)
				(type default)
			)
			(layer "B.SilkS")
		)
		(fp_rect
			(start 0.508 0.9398)
			(end -0.508 -0.9398)
			(stroke
				(width 0)
				(type default)
			)
			(fill no)
			(layer "B.CrtYd")
		)
		(fp_rect
			(start 0.508 0.9398)
			(end -0.508 -0.9398)
			(stroke
				(width 0)
				(type default)
			)
			(fill no)
			(layer "B.Fab")
		)
		(pad "1" smd custom
			(at 0 -0.4445 180)
			(size 0.1397 0.1397)
			(layers "B.Cu" "B.Mask" "B.Paste")
			(net "BMC0_SMB10_CLK")
			(options
				(clearance outline)
				(anchor circle)
			)
			(primitives
				(gr_poly
					(pts
						(arc
							(start -0.1778 0.2794)
							(mid -0.249642 0.249642)
							(end -0.2794 0.1778)
						)
						(arc
							(start -0.2794 -0.1778)
							(mid -0.249642 -0.249642)
							(end -0.1778 -0.2794)
						)
						(arc
							(start 0.1778 -0.2794)
							(mid 0.249642 -0.249642)
							(end 0.2794 -0.1778)
						)
						(arc
							(start 0.2794 0.1778)
							(mid 0.249642 0.249642)
							(end 0.1778 0.2794)
						)
					)
					(width 0)
					(fill yes)
				)
			)
		)
		(pad "2" smd custom
			(at 0 0.4445 180)
			(size 0.1397 0.1397)
			(layers "B.Cu" "B.Mask" "B.Paste")
			(net "BMC_I2C10_8536_SCL")
			(options
				(clearance outline)
				(anchor circle)
			)
			(primitives
				(gr_poly
					(pts
						(arc
							(start -0.1778 0.2794)
							(mid -0.249642 0.249642)
							(end -0.2794 0.1778)
						)
						(arc
							(start -0.2794 -0.1778)
							(mid -0.249642 -0.249642)
							(end -0.1778 -0.2794)
						)
						(arc
							(start 0.1778 -0.2794)
							(mid 0.249642 -0.249642)
							(end 0.2794 -0.1778)
						)
						(arc
							(start 0.2794 0.1778)
							(mid 0.249642 0.249642)
							(end 0.1778 0.2794)
						)
					)
					(width 0)
					(fill yes)
				)
			)
		)
	)
	(footprint ""
		(layer "B.Cu")
		(at 239.6236 -37.0332 180)
		(property "Reference" "R5"
			(at 0 0 0)
			(layer "B.SilkS")
			(hide yes)
			(effects
				(font
					(size 1.27 1.27)
				)
				(justify mirror)
			)
		)
		(property "Value" "33R1J-GP"
			(at 3.3274 -1.3335 180)
			(unlocked yes)
			(layer "B.Fab")
			(hide yes)
			(effects
				(font
					(size 1.016 1.016)
					(thickness 0.1524)
				)
				(justify mirror)
			)
		)
		(property "Device Type" "R0201H12"
			(at 3.3274 -2.8575 180)
			(unlocked yes)
			(layer "B.Fab")
			(hide yes)
			(effects
				(font
					(size 1.016 1.016)
					(thickness 0.1524)
				)
				(justify mirror)
			)
		)
		(duplicate_pad_numbers_are_jumpers no)
		(fp_rect
			(start 0.2794 0.6477)
			(end -0.2794 -0.6477)
			(stroke
				(width 0)
				(type default)
			)
			(fill no)
			(layer "B.CrtYd")
		)
		(fp_rect
			(start 0.2794 0.6477)
			(end -0.2794 -0.6477)
			(stroke
				(width 0)
				(type default)
			)
			(fill no)
			(layer "B.Fab")
		)
		(pad "1" smd custom
			(at 0 -0.2794)
			(size 0.0762 0.0762)
			(layers "B.Cu" "B.Mask" "B.Paste")
			(net "PCIE_REFCLK_D_N")
			(options
				(clearance outline)
				(anchor circle)
			)
			(primitives
				(gr_poly
					(pts
						(arc
							(start 0.1524 0.127)
							(mid 0.137521 0.162921)
							(end 0.1016 0.1778)
						)
						(arc
							(start -0.1016 0.1778)
							(mid -0.137521 0.162921)
							(end -0.1524 0.127)
						)
						(arc
							(start -0.1524 -0.127)
							(mid -0.137521 -0.162921)
							(end -0.1016 -0.1778)
						)
						(arc
							(start 0.1016 -0.1778)
							(mid 0.137521 -0.162921)
							(end 0.1524 -0.127)
						)
					)
					(width 0)
					(fill yes)
				)
			)
		)
		(pad "2" smd custom
			(at 0 0.2794)
			(size 0.0762 0.0762)
			(layers "B.Cu" "B.Mask" "B.Paste")
			(net "PCIE_REFCLK_D_P")
			(options
				(clearance outline)
				(anchor circle)
			)
			(primitives
				(gr_poly
					(pts
						(arc
							(start 0.1524 0.127)
							(mid 0.137521 0.162921)
							(end 0.1016 0.1778)
						)
						(arc
							(start -0.1016 0.1778)
							(mid -0.137521 0.162921)
							(end -0.1524 0.127)
						)
						(arc
							(start -0.1524 -0.127)
							(mid -0.137521 -0.162921)
							(end -0.1016 -0.1778)
						)
						(arc
							(start 0.1016 -0.1778)
							(mid 0.137521 -0.162921)
							(end 0.1524 -0.127)
						)
					)
					(width 0)
					(fill yes)
				)
			)
		)
	)
	(footprint ""
		(layer "B.Cu")
		(at 57.032652 -117.4242 -90)
		(property "Reference" "R242"
			(at 0 0 90)
			(layer "B.SilkS")
			(hide yes)
			(effects
				(font
					(size 1.27 1.27)
				)
				(justify mirror)
			)
		)
		(property "Value" "0R2J-2-GP"
			(at -0.064008 -3.993896 270)
			(unlocked yes)
			(layer "B.Fab")
			(hide yes)
			(effects
				(font
					(size 1.016 1.016)
					(thickness 0.1524)
				)
				(justify mirror)
			)
		)
		(property "Device Type" "R402H16"
			(at -0.064008 -5.517896 270)
			(unlocked yes)
			(layer "B.Fab")
			(hide yes)
			(effects
				(font
					(size 1.016 1.016)
					(thickness 0.1524)
				)
				(justify mirror)
			)
		)
		(duplicate_pad_numbers_are_jumpers no)
		(fp_line
			(start -0.508 -0.9398)
			(end 0.508 -0.9398)
			(stroke
				(width 0.1524)
				(type default)
			)
			(layer "B.SilkS")
		)
		(fp_line
			(start 0.508 -0.9398)
			(end 0.508 0.9398)
			(stroke
				(width 0.1524)
				(type default)
			)
			(layer "B.SilkS")
		)
		(fp_rect
			(start 0.508 0.9398)
			(end -0.508 -0.9398)
			(stroke
				(width 0)
				(type default)
			)
			(fill no)
			(layer "B.CrtYd")
		)
		(fp_rect
			(start 0.508 0.9398)
			(end -0.508 -0.9398)
			(stroke
				(width 0)
				(type default)
			)
			(fill no)
			(layer "B.Fab")
		)
		(pad "1" smd custom
			(at 0 -0.4445 90)
			(size 0.1397 0.1397)
			(layers "B.Cu" "B.Mask" "B.Paste")
			(net "BMC_I2C3_MINI3_SCL_S")
			(options
				(clearance outline)
				(anchor circle)
			)
			(primitives
				(gr_poly
					(pts
						(arc
							(start -0.1778 0.2794)
							(mid -0.249642 0.249642)
							(end -0.2794 0.1778)
						)
						(arc
							(start -0.2794 -0.1778)
							(mid -0.249642 -0.249642)
							(end -0.1778 -0.2794)
						)
						(arc
							(start 0.1778 -0.2794)
							(mid 0.249642 -0.249642)
							(end 0.2794 -0.1778)
						)
						(arc
							(start 0.2794 0.1778)
							(mid 0.249642 0.249642)
							(end 0.1778 0.2794)
						)
					)
					(width 0)
					(fill yes)
				)
			)
		)
		(pad "2" smd custom
			(at 0 0.4445 90)
			(size 0.1397 0.1397)
			(layers "B.Cu" "B.Mask" "B.Paste")
			(net "BMC0_SMB3_CLK")
			(options
				(clearance outline)
				(anchor circle)
			)
			(primitives
				(gr_poly
					(pts
						(arc
							(start -0.1778 0.2794)
							(mid -0.249642 0.249642)
							(end -0.2794 0.1778)
						)
						(arc
							(start -0.2794 -0.1778)
							(mid -0.249642 -0.249642)
							(end -0.1778 -0.2794)
						)
						(arc
							(start 0.1778 -0.2794)
							(mid 0.249642 -0.249642)
							(end 0.2794 -0.1778)
						)
						(arc
							(start 0.2794 0.1778)
							(mid 0.249642 0.249642)
							(end 0.1778 0.2794)
						)
					)
					(width 0)
					(fill yes)
				)
			)
		)
	)
	(footprint ""
		(layer "B.Cu")
		(at 134.62 -202.565)
		(property "Reference" "R142"
			(at 0 0 0)
			(layer "B.SilkS")
			(hide yes)
			(effects
				(font
					(size 1.27 1.27)
				)
				(justify mirror)
			)
		)
		(property "Value" "4K7R2F-GP"
			(at -0.064008 -3.993896 0)
			(unlocked yes)
			(layer "B.Fab")
			(hide yes)
			(effects
				(font
					(size 1.016 1.016)
					(thickness 0.1524)
				)
				(justify mirror)
			)
		)
		(property "Device Type" "R402H16"
			(at -0.064008 -5.517896 0)
			(unlocked yes)
			(layer "B.Fab")
			(hide yes)
			(effects
				(font
					(size 1.016 1.016)
					(thickness 0.1524)
				)
				(justify mirror)
			)
		)
		(duplicate_pad_numbers_are_jumpers no)
		(fp_line
			(start -0.508 -0.9398)
			(end 0.508 -0.9398)
			(stroke
				(width 0.1524)
				(type default)
			)
			(layer "B.SilkS")
		)
		(fp_line
			(start 0.508 -0.9398)
			(end 0.508 0.9398)
			(stroke
				(width 0.1524)
				(type default)
			)
			(layer "B.SilkS")
		)
		(fp_rect
			(start 0.508 0.9398)
			(end -0.508 -0.9398)
			(stroke
				(width 0)
				(type default)
			)
			(fill no)
			(layer "B.CrtYd")
		)
		(fp_rect
			(start 0.508 0.9398)
			(end -0.508 -0.9398)
			(stroke
				(width 0)
				(type default)
			)
			(fill no)
			(layer "B.Fab")
		)
		(pad "1" smd custom
			(at 0 -0.4445 180)
			(size 0.1397 0.1397)
			(layers "B.Cu" "B.Mask" "B.Paste")
			(net "BMC_SSD_RST#0_A6")
			(options
				(clearance outline)
				(anchor circle)
			)
			(primitives
				(gr_poly
					(pts
						(arc
							(start -0.1778 0.2794)
							(mid -0.249642 0.249642)
							(end -0.2794 0.1778)
						)
						(arc
							(start -0.2794 -0.1778)
							(mid -0.249642 -0.249642)
							(end -0.1778 -0.2794)
						)
						(arc
							(start 0.1778 -0.2794)
							(mid 0.249642 -0.249642)
							(end 0.2794 -0.1778)
						)
						(arc
							(start 0.2794 0.1778)
							(mid 0.249642 0.249642)
							(end 0.1778 0.2794)
						)
					)
					(width 0)
					(fill yes)
				)
			)
		)
		(pad "2" smd custom
			(at 0 0.4445 180)
			(size 0.1397 0.1397)
			(layers "B.Cu" "B.Mask" "B.Paste")
			(net "P3V3_STBY")
			(options
				(clearance outline)
				(anchor circle)
			)
			(primitives
				(gr_poly
					(pts
						(arc
							(start -0.1778 0.2794)
							(mid -0.249642 0.249642)
							(end -0.2794 0.1778)
						)
						(arc
							(start -0.2794 -0.1778)
							(mid -0.249642 -0.249642)
							(end -0.1778 -0.2794)
						)
						(arc
							(start 0.1778 -0.2794)
							(mid 0.249642 -0.249642)
							(end 0.2794 -0.1778)
						)
						(arc
							(start 0.2794 0.1778)
							(mid 0.249642 0.249642)
							(end 0.1778 0.2794)
						)
					)
					(width 0)
					(fill yes)
				)
			)
		)
	)
	(footprint ""
		(layer "B.Cu")
		(at 69.699124 -183.235092 180)
		(property "Reference" "R521"
			(at 0 0 0)
			(layer "B.SilkS")
			(hide yes)
			(effects
				(font
					(size 1.27 1.27)
				)
				(justify mirror)
			)
		)
		(property "Value" "10KR2F-2-GP"
			(at -0.064008 -3.993896 180)
			(unlocked yes)
			(layer "B.Fab")
			(hide yes)
			(effects
				(font
					(size 1.016 1.016)
					(thickness 0.1524)
				)
				(justify mirror)
			)
		)
		(property "Device Type" "R402H16"
			(at -0.064008 -5.517896 180)
			(unlocked yes)
			(layer "B.Fab")
			(hide yes)
			(effects
				(font
					(size 1.016 1.016)
					(thickness 0.1524)
				)
				(justify mirror)
			)
		)
		(duplicate_pad_numbers_are_jumpers no)
		(fp_line
			(start 0.508 -0.9398)
			(end 0.508 0.9398)
			(stroke
				(width 0.1524)
				(type default)
			)
			(layer "B.SilkS")
		)
		(fp_line
			(start -0.508 -0.9398)
			(end 0.508 -0.9398)
			(stroke
				(width 0.1524)
				(type default)
			)
			(layer "B.SilkS")
		)
		(fp_rect
			(start 0.508 0.9398)
			(end -0.508 -0.9398)
			(stroke
				(width 0)
				(type default)
			)
			(fill no)
			(layer "B.CrtYd")
		)
		(fp_rect
			(start 0.508 0.9398)
			(end -0.508 -0.9398)
			(stroke
				(width 0)
				(type default)
			)
			(fill no)
			(layer "B.Fab")
		)
		(pad "1" smd custom
			(at 0 -0.4445)
			(size 0.1397 0.1397)
			(layers "B.Cu" "B.Mask" "B.Paste")
			(net "P3V3_STBY")
			(options
				(clearance outline)
				(anchor circle)
			)
			(primitives
				(gr_poly
					(pts
						(arc
							(start -0.1778 0.2794)
							(mid -0.249642 0.249642)
							(end -0.2794 0.1778)
						)
						(arc
							(start -0.2794 -0.1778)
							(mid -0.249642 -0.249642)
							(end -0.1778 -0.2794)
						)
						(arc
							(start 0.1778 -0.2794)
							(mid 0.249642 -0.249642)
							(end 0.2794 -0.1778)
						)
						(arc
							(start 0.2794 0.1778)
							(mid 0.249642 0.249642)
							(end 0.1778 0.2794)
						)
					)
					(width 0)
					(fill yes)
				)
			)
		)
		(pad "2" smd custom
			(at 0 0.4445)
			(size 0.1397 0.1397)
			(layers "B.Cu" "B.Mask" "B.Paste")
			(net "IOEXP1_AD1")
			(options
				(clearance outline)
				(anchor circle)
			)
			(primitives
				(gr_poly
					(pts
						(arc
							(start -0.1778 0.2794)
							(mid -0.249642 0.249642)
							(end -0.2794 0.1778)
						)
						(arc
							(start -0.2794 -0.1778)
							(mid -0.249642 -0.249642)
							(end -0.1778 -0.2794)
						)
						(arc
							(start 0.1778 -0.2794)
							(mid 0.249642 -0.249642)
							(end 0.2794 -0.1778)
						)
						(arc
							(start 0.2794 0.1778)
							(mid 0.249642 0.249642)
							(end 0.1778 0.2794)
						)
					)
					(width 0)
					(fill yes)
				)
			)
		)
	)
	(footprint ""
		(layer "B.Cu")
		(at 56.134 -132.08)
		(property "Reference" "C8087"
			(at 0 0 0)
			(layer "B.SilkS")
			(hide yes)
			(effects
				(font
					(size 1.27 1.27)
				)
				(justify mirror)
			)
		)
		(property "Value" "SCD1U25V2KX-2-GP"
			(at -1.1811 -2.7051 0)
			(unlocked yes)
			(layer "B.Fab")
			(hide yes)
			(effects
				(font
					(size 1.016 1.016)
					(thickness 0.1524)
				)
				(justify mirror)
			)
		)
		(property "Device Type" "C402H22"
			(at -1.1811 -4.2291 0)
			(unlocked yes)
			(layer "B.Fab")
			(hide yes)
			(effects
				(font
					(size 1.016 1.016)
					(thickness 0.1524)
				)
				(justify mirror)
			)
		)
		(duplicate_pad_numbers_are_jumpers no)
		(fp_rect
			(start 0.4318 0.9525)
			(end -0.4318 -0.9525)
			(stroke
				(width 0)
				(type default)
			)
			(fill no)
			(layer "B.CrtYd")
		)
		(fp_rect
			(start 0.4318 0.9525)
			(end -0.4318 -0.9525)
			(stroke
				(width 0)
				(type default)
			)
			(fill no)
			(layer "B.Fab")
		)
		(pad "1" smd custom
			(at 0 -0.4445 180)
			(size 0.1524 0.1524)
			(layers "B.Cu" "B.Mask" "B.Paste")
			(net "ADC_P3V3_STBY")
			(options
				(clearance outline)
				(anchor circle)
			)
			(primitives
				(gr_poly
					(pts
						(arc
							(start 0.3048 0.2032)
							(mid 0.275042 0.275042)
							(end 0.2032 0.3048)
						)
						(arc
							(start -0.2032 0.3048)
							(mid -0.275042 0.275042)
							(end -0.3048 0.2032)
						)
						(arc
							(start -0.3048 -0.2032)
							(mid -0.275042 -0.275042)
							(end -0.2032 -0.3048)
						)
						(arc
							(start 0.2032 -0.3048)
							(mid 0.275042 -0.275042)
							(end 0.3048 -0.2032)
						)
					)
					(width 0)
					(fill yes)
				)
			)
		)
		(pad "2" smd custom
			(at 0 0.4445 180)
			(size 0.1524 0.1524)
			(layers "B.Cu" "B.Mask" "B.Paste")
			(net "GND")
			(options
				(clearance outline)
				(anchor circle)
			)
			(primitives
				(gr_poly
					(pts
						(arc
							(start 0.3048 0.2032)
							(mid 0.275042 0.275042)
							(end 0.2032 0.3048)
						)
						(arc
							(start -0.2032 0.3048)
							(mid -0.275042 0.275042)
							(end -0.3048 0.2032)
						)
						(arc
							(start -0.3048 -0.2032)
							(mid -0.275042 -0.275042)
							(end -0.2032 -0.3048)
						)
						(arc
							(start 0.2032 -0.3048)
							(mid 0.275042 -0.275042)
							(end 0.3048 -0.2032)
						)
					)
					(width 0)
					(fill yes)
				)
			)
		)
	)
	(footprint ""
		(layer "B.Cu")
		(at 224.079562 -194.05473)
		(property "Reference" "R3227"
			(at 0 0 0)
			(layer "B.SilkS")
			(hide yes)
			(effects
				(font
					(size 1.27 1.27)
				)
				(justify mirror)
			)
		)
		(property "Value" "0R2J-2-GP"
			(at -0.064008 -3.993896 0)
			(unlocked yes)
			(layer "B.Fab")
			(hide yes)
			(effects
				(font
					(size 1.016 1.016)
					(thickness 0.1524)
				)
				(justify mirror)
			)
		)
		(property "Device Type" "R402H16"
			(at -0.064008 -5.517896 0)
			(unlocked yes)
			(layer "B.Fab")
			(hide yes)
			(effects
				(font
					(size 1.016 1.016)
					(thickness 0.1524)
				)
				(justify mirror)
			)
		)
		(duplicate_pad_numbers_are_jumpers no)
		(fp_line
			(start -0.508 -0.9398)
			(end 0.508 -0.9398)
			(stroke
				(width 0.1524)
				(type default)
			)
			(layer "B.SilkS")
		)
		(fp_line
			(start 0.508 -0.9398)
			(end 0.508 0.9398)
			(stroke
				(width 0.1524)
				(type default)
			)
			(layer "B.SilkS")
		)
		(fp_rect
			(start 0.508 0.9398)
			(end -0.508 -0.9398)
			(stroke
				(width 0)
				(type default)
			)
			(fill no)
			(layer "B.CrtYd")
		)
		(fp_rect
			(start 0.508 0.9398)
			(end -0.508 -0.9398)
			(stroke
				(width 0)
				(type default)
			)
			(fill no)
			(layer "B.Fab")
		)
		(pad "1" smd custom
			(at 0 -0.4445 180)
			(size 0.1397 0.1397)
			(layers "B.Cu" "B.Mask" "B.Paste")
			(net "SSD_PERST_Y8")
			(options
				(clearance outline)
				(anchor circle)
			)
			(primitives
				(gr_poly
					(pts
						(arc
							(start -0.1778 0.2794)
							(mid -0.249642 0.249642)
							(end -0.2794 0.1778)
						)
						(arc
							(start -0.2794 -0.1778)
							(mid -0.249642 -0.249642)
							(end -0.1778 -0.2794)
						)
						(arc
							(start 0.1778 -0.2794)
							(mid 0.249642 -0.249642)
							(end 0.2794 -0.1778)
						)
						(arc
							(start 0.2794 0.1778)
							(mid 0.249642 0.249642)
							(end 0.1778 0.2794)
						)
					)
					(width 0)
					(fill yes)
				)
			)
		)
		(pad "2" smd custom
			(at 0 0.4445 180)
			(size 0.1397 0.1397)
			(layers "B.Cu" "B.Mask" "B.Paste")
			(net "SSD_PERST#8_R")
			(options
				(clearance outline)
				(anchor circle)
			)
			(primitives
				(gr_poly
					(pts
						(arc
							(start -0.1778 0.2794)
							(mid -0.249642 0.249642)
							(end -0.2794 0.1778)
						)
						(arc
							(start -0.2794 -0.1778)
							(mid -0.249642 -0.249642)
							(end -0.1778 -0.2794)
						)
						(arc
							(start 0.1778 -0.2794)
							(mid 0.249642 -0.249642)
							(end 0.2794 -0.1778)
						)
						(arc
							(start 0.2794 0.1778)
							(mid 0.249642 0.249642)
							(end 0.1778 0.2794)
						)
					)
					(width 0)
					(fill yes)
				)
			)
		)
	)
)
